FILE_TYPE = CONNECTIVITY;
{Allegro Design Entry HDL 17.2-2016 S081 (4005846) 1/11/2022}
"PAGE_NUMBER" = 328;
0"NC";
1"P12V_PSU\g";
2"P12V_AUX\g";
3"P12V_MAIN_R_0\g";
4"P12V_MAIN_R\g";
5"GND\g";
6"GND\g";
7"P12V_HSC_GATE_G1";
8"P12V_HSC_GATE_G2";
9"P12V_HSC_GATE_G5";
10"P12V_HSC_GATE_G6";
11"P12V_HSC_SENSE2_R3_N";
12"P12V_HSC_SENSE2_N";
13"P12V_HSC_SENSE2_R4_P";
14"P12V_HSC_GATE2";
15"P12V_HSC_SENSE2_R4_N";
16"P12V_HSC_ADC_P";
17"P12V_PSU_FUSE";
18"P12V_HSC_SENSE2_R1_N";
19"P12V_HSC_SENSE1_N";
20"P12V_HSC_SENSE2_R2_N";
21"P12V_HSC_SENSE2_R1_P";
22"P12V_HSC_GATE1";
23"P12V_HSC_GATE_G3";
24"P12V_HSC_SENSE2_R4_N";
25"P12V_HSC_SENSE2_R4_P";
26"P12V_HSC_SENSE2_R2_P";
27"P12V_HSC_SENSE2_R1_P";
28"P12V_HSC_SENSE2_P";
29"P12V_HSC_SENSE1_N";
30"P12V_HSC_SENSE2_R3_N";
31"P12V_HSC_SENSE2_R2_N";
32"P12V_HSC_SENSE2_R1_N";
33"P12V_HSC_ADC_N";
34"P12V_HSC_SENSE1_P";
35"P12V_HSC_SENSE2_R4_P";
36"P12V_HSC_SENSE2_R1_P";
37"P12V_HSC_SENSE2_R3_P";
38"P12V_HSC_SENSE2_R2_P";
39"P12V_HSC_GATE_G4";
40"MB0_CM_GATE_G0";
41"P12V_HSC_SENSE1_P";
42"P12V_HSC_SENSE2_R3_N";
43"P12V_HSC_SENSE2_R4_N";
44"P12V_HSC_SENSE2_R2_P";
45"P12V_HSC_SENSE2_R3_P";
46"P12V_HSC_SENSE2_R3_P";
47"P12V_HSC_SENSE2_R1_N";
48"P12V_HSC_SENSE2_R2_N";
49"P12V_HSC_GATE_RC";
%"Q_RES"
"1","(-2575,1575)","0","pure_quanta","I117";
;
PART_NUMBER"CS01002FB07"
MATERIAL"EMPTY"
TOLERANCE"1%"
VALUE"10"
ROOM"HSC1_BOM2"
LOCATION"PR2527"
CDS_LIB"pure_quanta"
PACK_TYPE"0402LF"
WATTAGE"1/16W"
$SEC"1"
CDS_SEC"1";
"B"
$PN"2"24;
"A"
$PN"1"12;
%"Q_RES"
"1","(-2575,1675)","0","pure_quanta","I118";
;
PART_NUMBER"CS01002FB07"
MATERIAL"EMPTY"
VALUE"10"
TOLERANCE"1%"
ROOM"HSC1_BOM2"
LOCATION"PR2526"
CDS_LIB"pure_quanta"
PACK_TYPE"0402LF"
WATTAGE"1/16W"
$SEC"1"
CDS_SEC"1";
"B"
$PN"2"42;
"A"
$PN"1"12;
%"Q_RES"
"1","(-2575,1875)","0","pure_quanta","I119";
;
PART_NUMBER"CS01002FB07"
MATERIAL"EMPTY"
TOLERANCE"1%"
VALUE"10"
ROOM"HSC1_BOM2"
LOCATION"PR2524"
WATTAGE"1/16W"
PACK_TYPE"0402LF"
CDS_LIB"pure_quanta"
$SEC"1"
CDS_SEC"1";
"B"
$PN"2"47;
"A"
$PN"1"12;
%"Q_RES"
"1","(-2575,1775)","0","pure_quanta","I120";
;
PART_NUMBER"CS01002FB07"
MATERIAL"EMPTY"
TOLERANCE"1%"
VALUE"10"
ROOM"HSC1_BOM2"
LOCATION"PR2525"
CDS_LIB"pure_quanta"
PACK_TYPE"0402LF"
WATTAGE"1/16W"
$SEC"1"
CDS_SEC"1";
"B"
$PN"2"48;
"A"
$PN"1"12;
%"Q_RES_4P_12"
"1","(2175,4325)","3","pure_quanta","I126";
;
PART_NUMBER"SP_CS+003DFR03_1"
WATTAGE"3W"
TOLERANCE"1%"
VALUE"0.003"
PART_TYPE"SMLF"
MATERIAL"EMPTY"
ROOM"HSC1_BOM2"
LOCATION"PR3"
CDS_LMAN_SYM_OUTLINE"-50,75,50,-75"
NEEDS_NO_SIZE"TRUE"
CDS_LIB"pure_quanta"
$SEC"1"
CDS_SEC"1";
"4"
$PN"4"19;
"3"
$PN"3"41;
"2"
$PN"2"3;
"1"
$PN"1"1;
%"Q_RES"
"2","(-875,675)","0","pure_quanta","I16";
;
PART_NUMBER"CS01002FB07"
VALUE"10"
TOLERANCE"1%"
PACK_TYPE"0402LF"
ROOM"HSC1_BOM2"
WATTAGE"1/16W"
MATERIAL"EMPTY"
LOCATION"PR2528"
CDS_LIB"pure_quanta"
$SEC"1"
CDS_SEC"1";
"A"
$PN"1"7;
"B"
$PN"2"14;
%"MOSFET_NCH_1D3S"
"1","(-525,1375)","6","pure_quanta","I35";
;
PART_NUMBER"BAMNR580000"
PART_TYPE"SMLF"
VALUE"PSMNR58-30YLH"
MATERIAL"EMPTY"
ROOM"HSC1_BOM2"
LOCATION"PPQ5"
CDS_LMAN_SYM_OUTLINE"-150,200,150,-200"
NEEDS_NO_SIZE"TRUE"
CDS_LIB"pure_quanta"
$SEC"1"
CDS_SEC"1";
"1"
$PN"1"2;
"4"
$PN"4"7;
"2"
$PN"2"2;
"5"
$PN"5"4;
"3"
$PN"3"2;
%"Q_RES"
"2","(0,675)","0","pure_quanta","I38";
;
PART_NUMBER"CS01002FB07"
VALUE"10"
WATTAGE"1/16W"
TOLERANCE"1%"
MATERIAL"EMPTY"
PACK_TYPE"0402LF"
ROOM"HSC1_BOM2"
LOCATION"PR2529"
CDS_LIB"pure_quanta"
$SEC"1"
CDS_SEC"1";
"A"
$PN"1"8;
"B"
$PN"2"14;
%"Q_RES"
"2","(850,675)","0","pure_quanta","I39";
;
PART_NUMBER"CS01002FB07"
MATERIAL"EMPTY"
VALUE"10"
TOLERANCE"1%"
PACK_TYPE"0402LF"
WATTAGE"1/16W"
ROOM"HSC1_BOM2"
LOCATION"PR2530"
CDS_LIB"pure_quanta"
$SEC"1"
CDS_SEC"1";
"A"
$PN"1"23;
"B"
$PN"2"14;
%"MOSFET_NCH_1D3S"
"1","(350,1400)","6","pure_quanta","I40";
;
PART_NUMBER"BAMNR580000"
VALUE"PSMNR58-30YLH"
PART_TYPE"SMLF"
MATERIAL"EMPTY"
ROOM"HSC1_BOM2"
LOCATION"PPQ6"
CDS_LIB"pure_quanta"
NEEDS_NO_SIZE"TRUE"
CDS_LMAN_SYM_OUTLINE"-150,200,150,-200"
$SEC"1"
CDS_SEC"1";
"1"
$PN"1"2;
"4"
$PN"4"8;
"2"
$PN"2"2;
"5"
$PN"5"4;
"3"
$PN"3"2;
%"MOSFET_NCH_1D3S"
"1","(1225,1425)","6","pure_quanta","I41";
;
PART_NUMBER"BAMNR580000"
MATERIAL"EMPTY"
PART_TYPE"SMLF"
VALUE"PSMNR58-30YLH"
ROOM"HSC1_BOM2"
LOCATION"PPQ7"
CDS_LIB"pure_quanta"
NEEDS_NO_SIZE"TRUE"
CDS_LMAN_SYM_OUTLINE"-150,200,150,-200"
$SEC"1"
CDS_SEC"1";
"1"
$PN"1"2;
"4"
$PN"4"23;
"2"
$PN"2"2;
"5"
$PN"5"4;
"3"
$PN"3"2;
%"ZENER_AC"
"1","(-450,3775)","1","pure_quanta","I51";
;
PART_NUMBER"BC0MDJ14000"
MATERIAL"IC"
VALUE"5.0SMDJ14A"
PART_TYPE"SMLF"
LOCATION"PD15"
NEEDS_NO_SIZE"TRUE"
CDS_LMAN_SYM_OUTLINE"-75,50,75,-50"
CDS_LIB"pure_quanta"
$SEC"1"
CDS_SEC"1";
"C"
$PN"C"17;
"A"
$PN"A"5;
%"GND"
"1","(50,3525)","0","logical_power","I52";
;
HDL_POWER"GND"
SIZE"1B"
CDS_LIB"logical_power"
ROOM"VR_DDR1_POWER_STAGE";
"A<SIZE-1..0>\NAC"5;
%"ZENER_AC"
"1","(50,3775)","1","pure_quanta","I53";
;
PART_NUMBER"BC0MDJ14000"
VALUE"5.0SMDJ14A"
PART_TYPE"SMLF"
MATERIAL"IC"
LOCATION"PD16"
NEEDS_NO_SIZE"TRUE"
CDS_LIB"pure_quanta"
CDS_LMAN_SYM_OUTLINE"-75,50,75,-50"
$SEC"1"
CDS_SEC"1";
"C"
$PN"C"17;
"A"
$PN"A"5;
%"Q_FUSE"
"1","(50,4125)","3","pure_quanta","I54";
;
PART_NUMBER"DKK00XFU000"
VALUE"20A/125V"
MATERIAL"IC"
PACK_TYPE"SMLF"
LOCATION"FS1"
CDS_LIB"pure_quanta"
NEEDS_NO_SIZE"TRUE"
$SEC"1"
CDS_SEC"1";
"2 \B"
$PN"2"17;
"1 \B"
$PN"1"1;
%"UNIVERSAL_POWER"
"1","(50,4400)","0","logical_power","I55";
;
HDL_POWER"P12V_PSU"
ROOM"AUX_SW"
BOM_COST"MIO_VRD_SB"
CDS_LIB"logical_power";
"A"1;
%"Q_RES"
"2","(1700,675)","0","pure_quanta","I59";
;
PART_NUMBER"CS01002FB07"
VALUE"10"
TOLERANCE"1%"
WATTAGE"1/16W"
MATERIAL"EMPTY"
PACK_TYPE"0402LF"
ROOM"HSC1_BOM2"
LOCATION"PR2531"
CDS_LIB"pure_quanta"
$SEC"1"
CDS_SEC"1";
"A"
$PN"1"39;
"B"
$PN"2"14;
%"Q_RES"
"2","(2550,675)","0","pure_quanta","I60";
;
PART_NUMBER"CS01002FB07"
WATTAGE"1/16W"
TOLERANCE"1%"
MATERIAL"EMPTY"
VALUE"10"
PACK_TYPE"0402LF"
ROOM"HSC1_BOM2"
LOCATION"PR2535"
CDS_LIB"pure_quanta"
$SEC"1"
CDS_SEC"1";
"A"
$PN"1"9;
"B"
$PN"2"14;
%"Q_RES"
"2","(3425,675)","0","pure_quanta","I61";
;
PART_NUMBER"CS01002FB07"
MATERIAL"EMPTY"
VALUE"10"
WATTAGE"1/16W"
TOLERANCE"1%"
PACK_TYPE"0402LF"
ROOM"HSC1_BOM2"
LOCATION"PR2536"
CDS_LIB"pure_quanta"
$SEC"1"
CDS_SEC"1";
"A"
$PN"1"10;
"B"
$PN"2"14;
%"MOSFET_NCH_1D3S"
"1","(2100,1425)","6","pure_quanta","I62";
;
PART_NUMBER"BAMNR580000"
VALUE"PSMNR58-30YLH"
MATERIAL"EMPTY"
PART_TYPE"SMLF"
ROOM"HSC1_BOM2"
LOCATION"PPQ8"
CDS_LMAN_SYM_OUTLINE"-150,200,150,-200"
NEEDS_NO_SIZE"TRUE"
CDS_LIB"pure_quanta"
$SEC"1"
CDS_SEC"1";
"1"
$PN"1"2;
"4"
$PN"4"39;
"2"
$PN"2"2;
"5"
$PN"5"4;
"3"
$PN"3"2;
%"Q_SP_RES4P"
"1","(2150,2325)","0","pure_quanta","I63";
;
PART_NUMBER"SP_CS0000FFT04"
VALUE"0.0003"
PART_TYPE"SMLF"
MATERIAL"EMPTY"
TOLERANCE"1%"
WATTAGE"4W"
ROOM"HSC1_BOM2"
LOCATION"PR2534"
NEEDS_NO_SIZE"TRUE"
CDS_LIB"pure_quanta"
CDS_LMAN_SYM_OUTLINE"-150,75,150,-75"
$SEC"1"
CDS_SEC"1";
"1A"
$PN"1A"1;
"2A"
$PN"2A"4;
"1B"
$PN"1B"13;
"2B"
$PN"2B"15;
%"Q_SP_RES4P"
"1","(2150,2925)","0","pure_quanta","I64";
;
PART_NUMBER"SP_CS0000FFT04"
MATERIAL"EMPTY"
PART_TYPE"SMLF"
VALUE"0.0003"
WATTAGE"4W"
TOLERANCE"1%"
ROOM"HSC1_BOM2"
LOCATION"PR2533"
CDS_LIB"pure_quanta"
CDS_LMAN_SYM_OUTLINE"-150,75,150,-75"
NEEDS_NO_SIZE"TRUE"
$SEC"1"
CDS_SEC"1";
"1A"
$PN"1A"1;
"2A"
$PN"2A"4;
"1B"
$PN"1B"45;
"2B"
$PN"2B"11;
%"MOSFET_NCH_1D3S"
"1","(2975,1450)","6","pure_quanta","I65";
;
PART_NUMBER"BAMNR580000"
PART_TYPE"SMLF"
MATERIAL"EMPTY"
VALUE"PSMNR58-30YLH"
ROOM"HSC1_BOM2"
LOCATION"PPQ1"
SEC_TYPE""
NEEDS_NO_SIZE"TRUE"
CDS_LMAN_SYM_OUTLINE"-150,200,150,-200"
CDS_LIB"pure_quanta"
SEC"1";
"1"
$PN"1"2;
"4"
$PN"4"9;
"2"
$PN"2"2;
"5"
$PN"5"4;
"3"
$PN"3"2;
%"Q_CAP"
"1","(4025,675)","0","pure_quanta","I68";
;
PART_NUMBER"CH3334K1B00"
VALUE"33NF"
MATERIAL"EMPTY"
TOLERANCE"10%"
VOLTAGE"25V"
PACK_TYPE"C0402"
LOCATION"PC1750"
CDS_LIB"pure_quanta"
$SEC"1"
CDS_SEC"1";
"B"
$PN"2"14;
"A"
$PN"1"2;
%"Q_CAP"
"1","(4500,375)","0","pure_quanta","I69";
;
PART_NUMBER"CH21006KB16"
MATERIAL"EMPTY"
VOLTAGE"50V"
VALUE"1NF"
TOLERANCE"10%"
PACK_TYPE"0402"
LOCATION"PC1751"
CDS_LIB"pure_quanta"
$SEC"1"
CDS_SEC"1";
"B"
$PN"2"14;
"A"
$PN"1"49;
%"Q_RES"
"2","(4500,700)","0","pure_quanta","I70";
;
PART_NUMBER"CS01002FB07"
WATTAGE"1/16W"
TOLERANCE"1%"
MATERIAL"EMPTY"
VALUE"10"
PACK_TYPE"0402LF"
LOCATION"PR2537"
CDS_LIB"pure_quanta"
$SEC"1"
CDS_SEC"1";
"A"
$PN"1"2;
"B"
$PN"2"49;
%"GND"
"1","(5200,-25)","0","logical_power","I71";
;
SIZE"1B"
HDL_POWER"GND"
ROOM"VR_DDR1_POWER_STAGE"
CDS_LIB"logical_power";
"A<SIZE-1..0>\NAC"6;
%"SS15P3SM386A"
"1","(5200,475)","1","pure_quanta","I72";
;
PART_NUMBER"BC015P3SZ00"
PART_TYPE"SMLF"
MATERIAL"IC"
VALUE"SS15P3S-M3/86A"
LOCATION"PD17"
NEEDS_NO_SIZE"TRUE"
CDS_LMAN_SYM_OUTLINE"-125,100,125,-100"
CDS_LIB"pure_quanta"
$SEC"1"
CDS_SEC"1";
"ANODE_2"
$PN"2"6;
"CATHODE"
$PN"K"2;
"ANODE_1"
$PN"1"6;
%"MOSFET_NCH_1D3S"
"1","(3850,1475)","6","pure_quanta","I73";
;
PART_NUMBER"BAMNR580000"
VALUE"PSMNR58-30YLH"
MATERIAL"EMPTY"
PART_TYPE"SMLF"
ROOM"HSC1_BOM2"
LOCATION"PPQ2"
SEC_TYPE""
CDS_LIB"pure_quanta"
CDS_LMAN_SYM_OUTLINE"-150,200,150,-200"
NEEDS_NO_SIZE"TRUE"
SEC"1";
"1"
$PN"1"2;
"4"
$PN"4"10;
"2"
$PN"2"2;
"5"
$PN"5"4;
"3"
$PN"3"2;
%"UNIVERSAL_POWER"
"1","(4825,1275)","0","logical_power","I75";
;
HDL_POWER"P12V_AUX"
CDS_LIB"logical_power"
ROOM"AUX_SW"
BOM_COST"MIO_VRD_SB";
"A"2;
%"Q_RES"
"2","(4800,2125)","0","pure_quanta","I76";
;
PART_NUMBER"CS01002FB07"
VALUE"10"
TOLERANCE"1%"
PACK_TYPE"0402LF"
MATERIAL"EMPTY"
WATTAGE"1/16W"
ROOM"HSC1_BOM2"
LOCATION"PR2538"
CDS_LIB"pure_quanta"
$SEC"1"
CDS_SEC"1";
"A"
$PN"1"40;
"B"
$PN"2"22;
%"MOSFET_NCH_1D3S"
"1","(5300,2625)","6","pure_quanta","I77";
;
PART_NUMBER"BAMNR580000"
VALUE"PSMNR58-30YLH"
MATERIAL"EMPTY"
PART_TYPE"SMLF"
ROOM"HSC1_BOM2"
LOCATION"PPQ9"
CDS_LMAN_SYM_OUTLINE"-150,200,150,-200"
CDS_LIB"pure_quanta"
NEEDS_NO_SIZE"TRUE"
$SEC"1"
CDS_SEC"1";
"1"
$PN"1"2;
"4"
$PN"4"40;
"2"
$PN"2"2;
"5"
$PN"5"3;
"3"
$PN"3"2;
%"Q_SP_RES4P"
"1","(2150,3500)","0","pure_quanta","I78";
;
PART_NUMBER"SP_CS0000FFT04"
VALUE"0.0003"
PART_TYPE"SMLF"
MATERIAL"EMPTY"
TOLERANCE"1%"
WATTAGE"4W"
ROOM"HSC1_BOM2"
LOCATION"PR2532"
CDS_LIB"pure_quanta"
CDS_LMAN_SYM_OUTLINE"-150,75,150,-75"
NEEDS_NO_SIZE"TRUE"
$SEC"1"
CDS_SEC"1";
"1A"
$PN"1A"1;
"2A"
$PN"2A"4;
"1B"
$PN"1B"44;
"2B"
$PN"2B"20;
%"Q_SP_RES4P"
"1","(2175,4050)","0","pure_quanta","I79";
;
PART_NUMBER"SP_CS0000FFT04"
PART_TYPE"SMLF"
MATERIAL"EMPTY"
VALUE"0.0003"
WATTAGE"4W"
TOLERANCE"1%"
ROOM"HSC1_BOM2"
LOCATION"PR4"
NEEDS_NO_SIZE"TRUE"
CDS_LMAN_SYM_OUTLINE"-150,75,150,-75"
CDS_LIB"pure_quanta"
SEC_TYPE""
SEC"1";
"1A"
$PN"1A"1;
"2A"
$PN"2A"4;
"1B"
$PN"1B"21;
"2B"
$PN"2B"18;
%"UNIVERSAL_POWER"
"1","(3925,4150)","0","logical_power","I84";
;
HDL_POWER"P12V_MAIN_R"
BOM_COST"MIO_VRD_SB"
ROOM"AUX_SW"
CDS_LIB"logical_power";
"A"4;
%"UNIVERSAL_POWER"
"1","(4325,4400)","0","logical_power","I85";
;
HDL_POWER"P12V_MAIN_R_0"
CDS_LIB"logical_power"
BOM_COST"MIO_VRD_SB"
ROOM"AUX_SW";
"A"3;
%"Q_RES"
"1","(-2600,2325)","0","pure_quanta","I86";
;
PART_NUMBER"CS-1002FB04"
MATERIAL"EMPTY"
TOLERANCE"1%"
VALUE"1"
ROOM"HSC1_BOM2"
LOCATION"PR2522"
CDS_LIB"pure_quanta"
PACK_TYPE"0402LF"
WATTAGE"1/16W"
$SEC"1"
CDS_SEC"1";
"B"
$PN"2"46;
"A"
$PN"1"28;
%"Q_RES"
"1","(-2600,2225)","0","pure_quanta","I87";
;
PART_NUMBER"CS-1002FB04"
VALUE"1"
MATERIAL"EMPTY"
TOLERANCE"1%"
ROOM"HSC1_BOM2"
LOCATION"PR2523"
CDS_LIB"pure_quanta"
PACK_TYPE"0402LF"
WATTAGE"1/16W"
$SEC"1"
CDS_SEC"1";
"B"
$PN"2"25;
"A"
$PN"1"28;
%"Q_RES"
"1","(-2600,2425)","0","pure_quanta","I88";
;
PART_NUMBER"CS-1002FB04"
MATERIAL"EMPTY"
TOLERANCE"1%"
VALUE"1"
ROOM"HSC1_BOM2"
LOCATION"PR2521"
CDS_LIB"pure_quanta"
PACK_TYPE"0402LF"
WATTAGE"1/16W"
$SEC"1"
CDS_SEC"1";
"B"
$PN"2"26;
"A"
$PN"1"28;
%"Q_RES"
"1","(-2600,2525)","0","pure_quanta","I89";
;
PART_NUMBER"CS-1002FB04"
MATERIAL"EMPTY"
TOLERANCE"1%"
VALUE"1"
ROOM"HSC1_BOM2"
LOCATION"PR2520"
WATTAGE"1/16W"
PACK_TYPE"0402LF"
CDS_LIB"pure_quanta"
$SEC"1"
CDS_SEC"1";
"B"
$PN"2"27;
"A"
$PN"1"28;
%"Q_RES"
"1","(-2600,3100)","0","pure_quanta","I90";
;
PART_NUMBER"CS01002FB07"
MATERIAL"EMPTY"
VALUE"10"
TOLERANCE"1%"
ROOM"HSC1_BOM2"
LOCATION"PR2517"
WATTAGE"1/16W"
PACK_TYPE"0402LF"
CDS_LIB"pure_quanta"
$SEC"1"
CDS_SEC"1";
"B"
$PN"2"30;
"A"
$PN"1"33;
%"Q_RES"
"1","(-2600,3000)","0","pure_quanta","I91";
;
PART_NUMBER"CS01002FB07"
MATERIAL"EMPTY"
TOLERANCE"1%"
VALUE"10"
ROOM"HSC1_BOM2"
LOCATION"PR2518"
PACK_TYPE"0402LF"
WATTAGE"1/16W"
CDS_LIB"pure_quanta"
$SEC"1"
CDS_SEC"1";
"B"
$PN"2"43;
"A"
$PN"1"33;
%"Q_RES"
"1","(-2600,2900)","0","pure_quanta","I92";
;
PART_NUMBER"CS11002FB07"
TOLERANCE"1%"
MATERIAL"EMPTY"
VALUE"100"
ROOM"HSC1_BOM2"
LOCATION"PR2519"
PACK_TYPE"0402LF"
WATTAGE"1/16W"
CDS_LIB"pure_quanta"
$SEC"1"
CDS_SEC"1";
"B"
$PN"2"29;
"A"
$PN"1"33;
%"Q_RES"
"1","(-2600,3300)","0","pure_quanta","I93";
;
PART_NUMBER"CS01002FB07"
MATERIAL"EMPTY"
TOLERANCE"1%"
VALUE"10"
ROOM"HSC1_BOM2"
LOCATION"PR2515"
CDS_LIB"pure_quanta"
PACK_TYPE"0402LF"
WATTAGE"1/16W"
$SEC"1"
CDS_SEC"1";
"B"
$PN"2"32;
"A"
$PN"1"33;
%"Q_RES"
"1","(-2600,3200)","0","pure_quanta","I94";
;
PART_NUMBER"CS01002FB07"
MATERIAL"EMPTY"
VALUE"10"
TOLERANCE"1%"
ROOM"HSC1_BOM2"
LOCATION"PR2516"
CDS_LIB"pure_quanta"
PACK_TYPE"0402LF"
WATTAGE"1/16W"
$SEC"1"
CDS_SEC"1";
"B"
$PN"2"31;
"A"
$PN"1"33;
%"Q_RES"
"1","(-2625,3750)","0","pure_quanta","I95";
;
PART_NUMBER"CS-1002FB04"
MATERIAL"EMPTY"
TOLERANCE"1%"
VALUE"1"
ROOM"HSC1_BOM2"
LOCATION"PR2513"
PACK_TYPE"0402LF"
WATTAGE"1/16W"
CDS_LIB"pure_quanta"
$SEC"1"
CDS_SEC"1";
"B"
$PN"2"35;
"A"
$PN"1"16;
%"Q_RES"
"1","(-2625,3850)","0","pure_quanta","I96";
;
PART_NUMBER"CS-1002FB04"
MATERIAL"EMPTY"
TOLERANCE"1%"
VALUE"1"
ROOM"HSC1_BOM2"
LOCATION"PR2512"
WATTAGE"1/16W"
PACK_TYPE"0402LF"
CDS_LIB"pure_quanta"
$SEC"1"
CDS_SEC"1";
"B"
$PN"2"37;
"A"
$PN"1"16;
%"Q_RES"
"1","(-2625,3650)","0","pure_quanta","I97";
;
PART_NUMBER"CS01002FB07"
MATERIAL"EMPTY"
VALUE"10"
TOLERANCE"1%"
ROOM"HSC1_BOM2"
LOCATION"PR2514"
WATTAGE"1/16W"
PACK_TYPE"0402LF"
CDS_LIB"pure_quanta"
$SEC"1"
CDS_SEC"1";
"B"
$PN"2"34;
"A"
$PN"1"16;
%"Q_RES"
"1","(-2625,4050)","0","pure_quanta","I98";
;
PART_NUMBER"CS-1002FB04"
MATERIAL"EMPTY"
TOLERANCE"1%"
VALUE"1"
ROOM"HSC1_BOM2"
LOCATION"PR2510"
WATTAGE"1/16W"
PACK_TYPE"0402LF"
CDS_LIB"pure_quanta"
$SEC"1"
CDS_SEC"1";
"B"
$PN"2"36;
"A"
$PN"1"16;
%"Q_RES"
"1","(-2625,3950)","0","pure_quanta","I99";
;
PART_NUMBER"CS-1002FB04"
MATERIAL"EMPTY"
TOLERANCE"1%"
VALUE"1"
ROOM"HSC1_BOM2"
LOCATION"PR2511"
WATTAGE"1/16W"
PACK_TYPE"0402LF"
CDS_LIB"pure_quanta"
$SEC"1"
CDS_SEC"1";
"B"
$PN"2"38;
"A"
$PN"1"16;
END.
